# S9S_MB_2U (Grand Teton) — schematic netlist excerpt (pin names and nets, part order shuffled) for the footprints in the layout excerpt that follows; sources: Cadence DE-HDL packaged netlist, KiCad conversion of 03242023_DA0F0TMBIJ0_F0T_Motherboard_J_brd_V01_OCP.brd

R21  Q_RES  0 5% CHIP  pkg 0402LF  page 16 : A = DBP_CPU_MBP1_GTL_N ; B = FM_PCH_TRIGGER1_N
PC1930  Q_CAPP  330UF 2.5V +10/-35% SPCAP  pkg SMLF  page 294 : A = PVCCFA_EHV_CPU1 ; B = GND

(kicad_pcb
	(version 20260206)
	(generator "pcbnew")
	(generator_version "10.0")
	(general
		(thickness 1.6)
		(legacy_teardrops no)
	)
	(paper "A4")
	(title_block
		(title "03242023_DA0F0TMBIJ0_F0T_Motherboard_J_brd_V01_OCP.brd")
		(comment 1 "Grand Teton / footprints 5939-5940 of 6105")
	)
	(layers
		(0 "F.Cu" signal "TOP")
		(4 "In1.Cu" signal "GND")
		(6 "In2.Cu" signal "IN1")
		(8 "In3.Cu" signal "GND1")
		(10 "In4.Cu" signal "IN2")
		(12 "In5.Cu" signal "GND2")
		(14 "In6.Cu" signal "IN3")
		(16 "In7.Cu" signal "GND3")
		(18 "In8.Cu" signal "VCC")
		(20 "In9.Cu" signal "VCC1")
		(22 "In10.Cu" signal "GND4")
		(24 "In11.Cu" signal "IN4")
		(26 "In12.Cu" signal "GND5")
		(28 "In13.Cu" signal "IN5")
		(30 "In14.Cu" signal "GND6")
		(32 "In15.Cu" signal "IN6")
		(34 "In16.Cu" signal "GND7")
		(2 "B.Cu" signal "BOTTOM")
		(9 "F.Adhes" user "F.Adhesive")
		(11 "B.Adhes" user "B.Adhesive")
		(13 "F.Paste" user "Package Geometry/Pastemask Top")
		(15 "B.Paste" user "Package Geometry/Pastemask Bottom")
		(5 "F.SilkS" user "Ref Des/Silkscreen Top")
		(7 "B.SilkS" user "Ref Des/Silkscreen Bottom")
		(1 "F.Mask" user "Board Geometry/Soldermask Top")
		(3 "B.Mask" user "Board Geometry/Soldermask Bottom")
		(17 "Dwgs.User" user "User.Drawings")
		(19 "Cmts.User" user "User.Comments")
		(21 "Eco1.User" user "User.Eco1")
		(23 "Eco2.User" user "User.Eco2")
		(25 "Edge.Cuts" user "Board Geometry/Outline")
		(27 "Margin" user)
		(31 "F.CrtYd" user "Package Geometry/Place Bound Top")
		(29 "B.CrtYd" user "Package Geometry/Place Bound Bottom")
		(35 "F.Fab" user "Ref Des/Assembly Top")
		(33 "B.Fab" user "Ref Des/Assembly Bottom")
	)
	(footprint ""
		(layer "B.Cu")
		(at 335.741264 -184.827926 90)
		(property "Reference" "R21"
			(at 0 0 90)
			(layer "B.SilkS")
			(hide yes)
			(effects
				(font
					(size 1.27 1.27)
				)
				(justify mirror)
			)
		)
		(property "Value" ""
			(at 0 0 90)
			(layer "B.Fab")
			(effects
				(font
					(size 1.27 1.27)
				)
				(justify mirror)
			)
		)
		(duplicate_pad_numbers_are_jumpers no)
		(fp_line
			(start 0.7874 -0.4064)
			(end -0.7874 -0.4064)
			(stroke
				(width 0.1524)
				(type default)
			)
			(layer "B.SilkS")
		)
		(fp_line
			(start -0.7874 -0.4064)
			(end -0.7874 0.4064)
			(stroke
				(width 0.1524)
				(type default)
			)
			(layer "B.SilkS")
		)
		(fp_line
			(start 0.7874 0.4064)
			(end 0.7874 -0.4064)
			(stroke
				(width 0.1524)
				(type default)
			)
			(layer "B.SilkS")
		)
		(fp_line
			(start -0.7874 0.4064)
			(end 0.7874 0.4064)
			(stroke
				(width 0.1524)
				(type default)
			)
			(layer "B.SilkS")
		)
		(fp_line
			(start 0.67945 -0.305054)
			(end 0.12065 -0.305054)
			(stroke
				(width 0.1)
				(type default)
			)
			(layer "B.Fab")
		)
		(fp_line
			(start 0.12065 -0.305054)
			(end 0.12065 -0.2794)
			(stroke
				(width 0.1)
				(type default)
			)
			(layer "B.Fab")
		)
		(fp_line
			(start -0.12065 -0.3048)
			(end -0.67945 -0.3048)
			(stroke
				(width 0.1)
				(type default)
			)
			(layer "B.Fab")
		)
		(fp_line
			(start -0.67945 -0.3048)
			(end -0.67945 0.3048)
			(stroke
				(width 0.1)
				(type default)
			)
			(layer "B.Fab")
		)
		(fp_line
			(start 0.12065 -0.2794)
			(end -0.12065 -0.2794)
			(stroke
				(width 0.1)
				(type default)
			)
			(layer "B.Fab")
		)
		(fp_line
			(start -0.12065 -0.2794)
			(end -0.12065 -0.3048)
			(stroke
				(width 0.1)
				(type default)
			)
			(layer "B.Fab")
		)
		(fp_line
			(start 0.12065 0.2794)
			(end 0.12065 0.3048)
			(stroke
				(width 0.1)
				(type default)
			)
			(layer "B.Fab")
		)
		(fp_line
			(start -0.120396 0.2794)
			(end 0.12065 0.2794)
			(stroke
				(width 0.1)
				(type default)
			)
			(layer "B.Fab")
		)
		(fp_line
			(start 0.67945 0.3048)
			(end 0.67945 -0.305054)
			(stroke
				(width 0.1)
				(type default)
			)
			(layer "B.Fab")
		)
		(fp_line
			(start 0.12065 0.3048)
			(end 0.67945 0.3048)
			(stroke
				(width 0.1)
				(type default)
			)
			(layer "B.Fab")
		)
		(fp_line
			(start -0.120396 0.3048)
			(end -0.120396 0.2794)
			(stroke
				(width 0.1)
				(type default)
			)
			(layer "B.Fab")
		)
		(fp_line
			(start -0.67945 0.3048)
			(end -0.120396 0.3048)
			(stroke
				(width 0.1)
				(type default)
			)
			(layer "B.Fab")
		)
		(pad "1" smd circle
			(at 0.40005 0 270)
			(size 0 0)
			(layers "B.Cu" "B.Mask" "B.Paste")
			(net "DBP_CPU_MBP1_GTL_N")
		)
		(pad "2" smd circle
			(at -0.40005 0 270)
			(size 0 0)
			(layers "B.Cu" "B.Mask" "B.Paste")
			(net "FM_PCH_TRIGGER1_N")
		)
	)
	(footprint ""
		(layer "B.Cu")
		(at 60.082684 -174.152306)
		(property "Reference" "PC1930"
			(at 0 0 0)
			(layer "B.SilkS")
			(hide yes)
			(effects
				(font
					(size 1.27 1.27)
				)
				(justify mirror)
			)
		)
		(property "Value" ""
			(at 0 0 0)
			(layer "B.Fab")
			(effects
				(font
					(size 1.27 1.27)
				)
				(justify mirror)
			)
		)
		(duplicate_pad_numbers_are_jumpers no)
		(fp_line
			(start -4.533392 -2.249932)
			(end -4.533392 2.249932)
			(stroke
				(width 0.1524)
				(type default)
			)
			(layer "B.SilkS")
		)
		(fp_line
			(start -4.533392 2.249932)
			(end 4.533392 2.249932)
			(stroke
				(width 0.1524)
				(type default)
			)
			(layer "B.SilkS")
		)
		(fp_line
			(start 4.533392 -2.249932)
			(end -4.533392 -2.249932)
			(stroke
				(width 0.1524)
				(type default)
			)
			(layer "B.SilkS")
		)
		(fp_line
			(start 4.533392 2.249932)
			(end 4.533392 -2.249932)
			(stroke
				(width 0.1524)
				(type default)
			)
			(layer "B.SilkS")
		)
		(fp_rect
			(start 4.533392 2.326132)
			(end 5.39242 -2.326132)
			(stroke
				(width 0)
				(type default)
			)
			(fill yes)
			(layer "B.SilkS")
		)
		(fp_line
			(start -3.750056 -2.249932)
			(end -3.750056 2.249932)
			(stroke
				(width 0.1)
				(type default)
			)
			(layer "B.Fab")
		)
		(fp_line
			(start -3.750056 2.249932)
			(end 3.750056 2.249932)
			(stroke
				(width 0.1)
				(type default)
			)
			(layer "B.Fab")
		)
		(fp_line
			(start 3.750056 -2.249932)
			(end -3.750056 -2.249932)
			(stroke
				(width 0.1)
				(type default)
			)
			(layer "B.Fab")
		)
		(fp_line
			(start 3.750056 2.249932)
			(end 3.750056 -2.249932)
			(stroke
				(width 0.1)
				(type default)
			)
			(layer "B.Fab")
		)
		(fp_text user "-"
			(at -4.8514 -0.14605 0)
			(unlocked yes)
			(layer "B.SilkS")
			(effects
				(font
					(size 1.905 1.4224)
					(thickness 0.1524)
				)
				(justify left mirror)
			)
		)
		(fp_text user "+"
			(at 6.322314 0.786384 270)
			(unlocked yes)
			(layer "B.SilkS")
			(effects
				(font
					(size 1.905 1.4224)
					(thickness 0.1524)
				)
				(justify left mirror)
			)
		)
		(fp_text user "-"
			(at -4.8514 -0.14605 0)
			(unlocked yes)
			(layer "B.Fab")
			(effects
				(font
					(size 1.905 1.4224)
					(thickness 0.1524)
				)
				(justify left mirror)
			)
		)
		(fp_text user "+"
			(at 6.322314 0.786384 270)
			(unlocked yes)
			(layer "B.Fab")
			(effects
				(font
					(size 1.905 1.4224)
					(thickness 0.1524)
				)
				(justify left mirror)
			)
		)
		(pad "1" smd rect
			(at 3.199892 0 180)
			(size 2.413 2.8194)
			(layers "B.Cu" "B.Mask" "B.Paste")
			(net "PVCCFA_EHV_CPU1")
		)
		(pad "2" smd rect
			(at -3.199892 0 180)
			(size 2.413 2.8194)
			(layers "B.Cu" "B.Mask" "B.Paste")
			(net "GND")
		)
	)
)
